# SCM (Grand Teton) — schematic netlist excerpt (pin names and nets, part order shuffled) for the footprints in the layout excerpt that follows; sources: Cadence DE-HDL packaged netlist, KiCad conversion of 12092022_DA0F0TMDCD0_F0T_Management_Board_D_brd_V3_OCP.brd

R129  Q_RES  22 1% CHIP  pkg 0402LF  page 12 : A = ESPI_LPC_D1_IO1 ; B = ESPI_LPC_LAD1_IO1
R40  Q_RES  2K 1% EMPTY  pkg 0402LF  page 11 : A = GND ; B = PWRGD_SYS_PWROK

(kicad_pcb
	(version 20260206)
	(generator "pcbnew")
	(generator_version "10.0")
	(general
		(thickness 1.6)
		(legacy_teardrops no)
	)
	(paper "A4")
	(title_block
		(title "12092022_DA0F0TMDCD0_F0T_Management_Board_D_brd_V3_OCP.brd")
		(comment 1 "Grand Teton / footprints 1251-1252 of 1440")
	)
	(layers
		(0 "F.Cu" signal "TOP")
		(4 "In1.Cu" signal "GND")
		(6 "In2.Cu" signal "IN1")
		(8 "In3.Cu" signal "GND1")
		(10 "In4.Cu" signal "IN2")
		(12 "In5.Cu" signal "VCC")
		(14 "In6.Cu" signal "VCC1")
		(16 "In7.Cu" signal "IN3")
		(18 "In8.Cu" signal "GND2")
		(20 "In9.Cu" signal "IN4")
		(22 "In10.Cu" signal "GND3")
		(2 "B.Cu" signal "BOTTOM")
		(9 "F.Adhes" user "F.Adhesive")
		(11 "B.Adhes" user "B.Adhesive")
		(13 "F.Paste" user "Package Geometry/Pastemask Top")
		(15 "B.Paste" user "Package Geometry/Pastemask Bottom")
		(5 "F.SilkS" user "Ref Des/Silkscreen Top")
		(7 "B.SilkS" user "Ref Des/Silkscreen Bottom")
		(1 "F.Mask" user "Board Geometry/Soldermask Top")
		(3 "B.Mask" user "Board Geometry/Soldermask Bottom")
		(17 "Dwgs.User" user "User.Drawings")
		(19 "Cmts.User" user "User.Comments")
		(21 "Eco1.User" user "User.Eco1")
		(23 "Eco2.User" user "User.Eco2")
		(25 "Edge.Cuts" user "Board Geometry/Outline")
		(27 "Margin" user)
		(31 "F.CrtYd" user "Package Geometry/Place Bound Top")
		(29 "B.CrtYd" user "Package Geometry/Place Bound Bottom")
		(35 "F.Fab" user "Ref Des/Assembly Top")
		(33 "B.Fab" user "Ref Des/Assembly Bottom")
	)
	(footprint ""
		(layer "B.Cu")
		(at 66.4972 -62.0268 -90)
		(property "Reference" "R129"
			(at 0 0 90)
			(layer "B.SilkS")
			(hide yes)
			(effects
				(font
					(size 1.27 1.27)
				)
				(justify mirror)
			)
		)
		(property "Value" ""
			(at 0 0 90)
			(layer "B.Fab")
			(effects
				(font
					(size 1.27 1.27)
				)
				(justify mirror)
			)
		)
		(duplicate_pad_numbers_are_jumpers no)
		(fp_line
			(start -0.7874 0.4064)
			(end 0.7874 0.4064)
			(stroke
				(width 0.1524)
				(type default)
			)
			(layer "B.SilkS")
		)
		(fp_line
			(start 0.7874 0.4064)
			(end 0.7874 -0.4064)
			(stroke
				(width 0.1524)
				(type default)
			)
			(layer "B.SilkS")
		)
		(fp_line
			(start -0.7874 -0.4064)
			(end -0.7874 0.4064)
			(stroke
				(width 0.1524)
				(type default)
			)
			(layer "B.SilkS")
		)
		(fp_line
			(start 0.7874 -0.4064)
			(end -0.7874 -0.4064)
			(stroke
				(width 0.1524)
				(type default)
			)
			(layer "B.SilkS")
		)
		(fp_line
			(start -0.67945 0.3048)
			(end -0.120396 0.3048)
			(stroke
				(width 0.1)
				(type default)
			)
			(layer "B.Fab")
		)
		(fp_line
			(start -0.120396 0.3048)
			(end -0.120396 0.2794)
			(stroke
				(width 0.1)
				(type default)
			)
			(layer "B.Fab")
		)
		(fp_line
			(start 0.12065 0.3048)
			(end 0.67945 0.3048)
			(stroke
				(width 0.1)
				(type default)
			)
			(layer "B.Fab")
		)
		(fp_line
			(start 0.67945 0.3048)
			(end 0.67945 -0.305054)
			(stroke
				(width 0.1)
				(type default)
			)
			(layer "B.Fab")
		)
		(fp_line
			(start -0.120396 0.2794)
			(end 0.12065 0.2794)
			(stroke
				(width 0.1)
				(type default)
			)
			(layer "B.Fab")
		)
		(fp_line
			(start 0.12065 0.2794)
			(end 0.12065 0.3048)
			(stroke
				(width 0.1)
				(type default)
			)
			(layer "B.Fab")
		)
		(fp_line
			(start -0.12065 -0.2794)
			(end -0.12065 -0.3048)
			(stroke
				(width 0.1)
				(type default)
			)
			(layer "B.Fab")
		)
		(fp_line
			(start 0.12065 -0.2794)
			(end -0.12065 -0.2794)
			(stroke
				(width 0.1)
				(type default)
			)
			(layer "B.Fab")
		)
		(fp_line
			(start -0.67945 -0.3048)
			(end -0.67945 0.3048)
			(stroke
				(width 0.1)
				(type default)
			)
			(layer "B.Fab")
		)
		(fp_line
			(start -0.12065 -0.3048)
			(end -0.67945 -0.3048)
			(stroke
				(width 0.1)
				(type default)
			)
			(layer "B.Fab")
		)
		(fp_line
			(start 0.12065 -0.305054)
			(end 0.12065 -0.2794)
			(stroke
				(width 0.1)
				(type default)
			)
			(layer "B.Fab")
		)
		(fp_line
			(start 0.67945 -0.305054)
			(end 0.12065 -0.305054)
			(stroke
				(width 0.1)
				(type default)
			)
			(layer "B.Fab")
		)
		(pad "1" smd circle
			(at 0.40005 0 90)
			(size 0 0)
			(layers "B.Cu" "B.Mask" "B.Paste")
			(net "ESPI_LPC_D1_IO1")
		)
		(pad "2" smd circle
			(at -0.40005 0 90)
			(size 0 0)
			(layers "B.Cu" "B.Mask" "B.Paste")
			(net "ESPI_LPC_LAD1_IO1")
		)
	)
	(footprint ""
		(layer "B.Cu")
		(at 23.573486 -106.50982 -90)
		(property "Reference" "R40"
			(at 0 0 90)
			(layer "B.SilkS")
			(hide yes)
			(effects
				(font
					(size 1.27 1.27)
				)
				(justify mirror)
			)
		)
		(property "Value" ""
			(at 0 0 90)
			(layer "B.Fab")
			(effects
				(font
					(size 1.27 1.27)
				)
				(justify mirror)
			)
		)
		(duplicate_pad_numbers_are_jumpers no)
		(fp_line
			(start -0.7874 0.4064)
			(end 0.7874 0.4064)
			(stroke
				(width 0.1524)
				(type default)
			)
			(layer "B.SilkS")
		)
		(fp_line
			(start 0.7874 0.4064)
			(end 0.7874 -0.4064)
			(stroke
				(width 0.1524)
				(type default)
			)
			(layer "B.SilkS")
		)
		(fp_line
			(start -0.7874 -0.4064)
			(end -0.7874 0.4064)
			(stroke
				(width 0.1524)
				(type default)
			)
			(layer "B.SilkS")
		)
		(fp_line
			(start 0.7874 -0.4064)
			(end -0.7874 -0.4064)
			(stroke
				(width 0.1524)
				(type default)
			)
			(layer "B.SilkS")
		)
		(fp_line
			(start -0.67945 0.3048)
			(end -0.120396 0.3048)
			(stroke
				(width 0.1)
				(type default)
			)
			(layer "B.Fab")
		)
		(fp_line
			(start -0.120396 0.3048)
			(end -0.120396 0.2794)
			(stroke
				(width 0.1)
				(type default)
			)
			(layer "B.Fab")
		)
		(fp_line
			(start 0.12065 0.3048)
			(end 0.67945 0.3048)
			(stroke
				(width 0.1)
				(type default)
			)
			(layer "B.Fab")
		)
		(fp_line
			(start 0.67945 0.3048)
			(end 0.67945 -0.305054)
			(stroke
				(width 0.1)
				(type default)
			)
			(layer "B.Fab")
		)
		(fp_line
			(start -0.120396 0.2794)
			(end 0.12065 0.2794)
			(stroke
				(width 0.1)
				(type default)
			)
			(layer "B.Fab")
		)
		(fp_line
			(start 0.12065 0.2794)
			(end 0.12065 0.3048)
			(stroke
				(width 0.1)
				(type default)
			)
			(layer "B.Fab")
		)
		(fp_line
			(start -0.12065 -0.2794)
			(end -0.12065 -0.3048)
			(stroke
				(width 0.1)
				(type default)
			)
			(layer "B.Fab")
		)
		(fp_line
			(start 0.12065 -0.2794)
			(end -0.12065 -0.2794)
			(stroke
				(width 0.1)
				(type default)
			)
			(layer "B.Fab")
		)
		(fp_line
			(start -0.67945 -0.3048)
			(end -0.67945 0.3048)
			(stroke
				(width 0.1)
				(type default)
			)
			(layer "B.Fab")
		)
		(fp_line
			(start -0.12065 -0.3048)
			(end -0.67945 -0.3048)
			(stroke
				(width 0.1)
				(type default)
			)
			(layer "B.Fab")
		)
		(fp_line
			(start 0.12065 -0.305054)
			(end 0.12065 -0.2794)
			(stroke
				(width 0.1)
				(type default)
			)
			(layer "B.Fab")
		)
		(fp_line
			(start 0.67945 -0.305054)
			(end 0.12065 -0.305054)
			(stroke
				(width 0.1)
				(type default)
			)
			(layer "B.Fab")
		)
		(pad "1" smd circle
			(at 0.40005 0 90)
			(size 0 0)
			(layers "B.Cu" "B.Mask" "B.Paste")
			(net "GND")
		)
		(pad "2" smd circle
			(at -0.40005 0 90)
			(size 0 0)
			(layers "B.Cu" "B.Mask" "B.Paste")
			(net "PWRGD_SYS_PWROK")
		)
	)
)
